# T6G (Grand Teton) — schematic netlist excerpt (pin names and nets, part order shuffled) for the footprints in the layout excerpt that follows; sources: Cadence DE-HDL packaged netlist, KiCad conversion of 04192023_DAF0TMB3IC0_F0TG_MB_C_brd_V02_OCP.brd

R4577  Q_RES  0 5% EMPTY  pkg 0402LF  page 125 : A = GPU_3V3IO_RSVD3_FFU ; B = GPU_3V3IO_RSVD3_FFU_ISO

PL10  Q_INDUCTOR4P_14  150NH IND  pkg L_TLM117513Q-151QL_11X7-5XA  page 201
  \1\  = SW_PVDDCR_CPU1_P0_SW1
  \2\  = IND_CPU1_P0_CPL5
  \3\  = IND_CPU1_P0_CPL1
  \4\  = PVDDCR_CPU1_P0

(kicad_pcb
	(version 20260206)
	(generator "pcbnew")
	(generator_version "10.0")
	(general
		(thickness 1.6)
		(legacy_teardrops no)
	)
	(paper "A4")
	(title_block
		(title "04192023_DAF0TMB3IC0_F0TG_MB_C_brd_V02_OCP.brd")
		(comment 1 "Grand Teton / footprints 2151-2152 of 8354")
	)
	(layers
		(0 "F.Cu" signal "TOP")
		(4 "In1.Cu" signal "GND")
		(6 "In2.Cu" signal "IN1")
		(8 "In3.Cu" signal "GND1")
		(10 "In4.Cu" signal "IN2")
		(12 "In5.Cu" signal "GND2")
		(14 "In6.Cu" signal "IN3")
		(16 "In7.Cu" signal "GND3")
		(18 "In8.Cu" signal "VCC")
		(20 "In9.Cu" signal "VCC1")
		(22 "In10.Cu" signal "GND4")
		(24 "In11.Cu" signal "IN4")
		(26 "In12.Cu" signal "GND5")
		(28 "In13.Cu" signal "IN5")
		(30 "In14.Cu" signal "GND6")
		(32 "In15.Cu" signal "IN6")
		(34 "In16.Cu" signal "GND7")
		(2 "B.Cu" signal "BOTTOM")
		(9 "F.Adhes" user "F.Adhesive")
		(11 "B.Adhes" user "B.Adhesive")
		(13 "F.Paste" user "Package Geometry/Pastemask Top")
		(15 "B.Paste" user "Package Geometry/Pastemask Bottom")
		(5 "F.SilkS" user "Ref Des/Silkscreen Top")
		(7 "B.SilkS" user "Ref Des/Silkscreen Bottom")
		(1 "F.Mask" user "Board Geometry/Soldermask Top")
		(3 "B.Mask" user "Board Geometry/Soldermask Bottom")
		(17 "Dwgs.User" user "User.Drawings")
		(19 "Cmts.User" user "User.Comments")
		(21 "Eco1.User" user "User.Eco1")
		(23 "Eco2.User" user "User.Eco2")
		(25 "Edge.Cuts" user "Board Geometry/Outline")
		(27 "Margin" user)
		(31 "F.CrtYd" user "Package Geometry/Place Bound Top")
		(29 "B.CrtYd" user "Package Geometry/Place Bound Bottom")
		(35 "F.Fab" user "Ref Des/Assembly Top")
		(33 "B.Fab" user "Ref Des/Assembly Bottom")
	)
	(footprint ""
		(layer "F.Cu")
		(at 335.176876 -325.656448)
		(property "Reference" "PL10"
			(at -3.115056 -15.887446 0)
			(unlocked yes)
			(layer "F.SilkS")
			(effects
				(font
					(size 0.7874 0.5842)
					(thickness 0.1524)
				)
				(justify left)
			)
		)
		(property "Value" ""
			(at 0 0 0)
			(layer "F.Fab")
			(effects
				(font
					(size 1.27 1.27)
				)
			)
		)
		(duplicate_pad_numbers_are_jumpers no)
		(fp_line
			(start -3.750056 -5.500116)
			(end -2.393442 -5.500116)
			(stroke
				(width 0.1524)
				(type default)
			)
			(layer "F.SilkS")
		)
		(fp_line
			(start -3.750056 5.500116)
			(end -3.750056 -5.500116)
			(stroke
				(width 0.1524)
				(type default)
			)
			(layer "F.SilkS")
		)
		(fp_line
			(start -2.393442 5.500116)
			(end -3.750056 5.500116)
			(stroke
				(width 0.1524)
				(type default)
			)
			(layer "F.SilkS")
		)
		(fp_line
			(start 2.393442 5.500116)
			(end 3.750056 5.500116)
			(stroke
				(width 0.1524)
				(type default)
			)
			(layer "F.SilkS")
		)
		(fp_line
			(start 3.750056 -5.500116)
			(end 2.393442 -5.500116)
			(stroke
				(width 0.1524)
				(type default)
			)
			(layer "F.SilkS")
		)
		(fp_line
			(start 3.750056 5.500116)
			(end 3.750056 -5.500116)
			(stroke
				(width 0.1524)
				(type default)
			)
			(layer "F.SilkS")
		)
		(fp_poly
			(pts
				(xy -3.9116 -4.249928) (xy -4.3434 -4.034028) (xy -4.3434 -4.465828)
			)
			(stroke
				(width 0)
				(type default)
			)
			(fill yes)
			(layer "F.SilkS")
		)
		(fp_line
			(start -3.750056 -5.500116)
			(end -3.750056 5.500116)
			(stroke
				(width 0.1)
				(type default)
			)
			(layer "F.Fab")
		)
		(fp_line
			(start -3.750056 5.500116)
			(end 3.750056 5.500116)
			(stroke
				(width 0.1)
				(type default)
			)
			(layer "F.Fab")
		)
		(fp_line
			(start 3.750056 -5.500116)
			(end -3.750056 -5.500116)
			(stroke
				(width 0.1)
				(type default)
			)
			(layer "F.Fab")
		)
		(fp_line
			(start 3.750056 5.500116)
			(end 3.750056 -5.500116)
			(stroke
				(width 0.1)
				(type default)
			)
			(layer "F.Fab")
		)
		(fp_poly
			(pts
				(xy -4.9276 -4.757928) (xy -4.9276 -3.741928) (xy -3.9116 -4.249928)
			)
			(stroke
				(width 0)
				(type default)
			)
			(fill yes)
			(layer "F.Fab")
		)
		(pad "1" smd rect
			(at 0 -4.249928 270)
			(size 2.413 4.5212)
			(layers "F.Cu" "F.Mask" "F.Paste")
			(net "SW_PVDDCR_CPU1_P0_SW1")
		)
		(pad "2" smd rect
			(at 0 -1.175004 270)
			(size 1.3716 4.5212)
			(layers "F.Cu" "F.Mask" "F.Paste")
			(net "IND_CPU1_P0_CPL5")
		)
		(pad "3" smd rect
			(at 0 1.175004 270)
			(size 1.3716 4.5212)
			(layers "F.Cu" "F.Mask" "F.Paste")
			(net "IND_CPU1_P0_CPL1")
		)
		(pad "4" smd rect
			(at 0 4.249928 270)
			(size 2.413 4.5212)
			(layers "F.Cu" "F.Mask" "F.Paste")
			(net "PVDDCR_CPU1_P0")
		)
	)
	(footprint ""
		(layer "F.Cu")
		(at 303.323498 -429.2219 180)
		(property "Reference" "R4577"
			(at 0 0 180)
			(layer "F.SilkS")
			(hide yes)
			(effects
				(font
					(size 1.27 1.27)
				)
			)
		)
		(property "Value" ""
			(at 0 0 180)
			(layer "F.Fab")
			(effects
				(font
					(size 1.27 1.27)
				)
			)
		)
		(duplicate_pad_numbers_are_jumpers no)
		(fp_line
			(start 0.7874 0.4064)
			(end -0.7874 0.4064)
			(stroke
				(width 0.1524)
				(type default)
			)
			(layer "F.SilkS")
		)
		(fp_line
			(start 0.7874 -0.4064)
			(end 0.7874 0.4064)
			(stroke
				(width 0.1524)
				(type default)
			)
			(layer "F.SilkS")
		)
		(fp_line
			(start -0.7874 0.4064)
			(end -0.7874 -0.4064)
			(stroke
				(width 0.1524)
				(type default)
			)
			(layer "F.SilkS")
		)
		(fp_line
			(start -0.7874 -0.4064)
			(end 0.7874 -0.4064)
			(stroke
				(width 0.1524)
				(type default)
			)
			(layer "F.SilkS")
		)
		(fp_line
			(start 0.67945 0.3048)
			(end 0.120396 0.3048)
			(stroke
				(width 0.1)
				(type default)
			)
			(layer "F.Fab")
		)
		(fp_line
			(start 0.67945 -0.3048)
			(end 0.67945 0.3048)
			(stroke
				(width 0.1)
				(type default)
			)
			(layer "F.Fab")
		)
		(fp_line
			(start 0.12065 -0.2794)
			(end 0.12065 -0.3048)
			(stroke
				(width 0.1)
				(type default)
			)
			(layer "F.Fab")
		)
		(fp_line
			(start 0.12065 -0.3048)
			(end 0.67945 -0.3048)
			(stroke
				(width 0.1)
				(type default)
			)
			(layer "F.Fab")
		)
		(fp_line
			(start 0.120396 0.3048)
			(end 0.120396 0.2794)
			(stroke
				(width 0.1)
				(type default)
			)
			(layer "F.Fab")
		)
		(fp_line
			(start 0.120396 0.2794)
			(end -0.12065 0.2794)
			(stroke
				(width 0.1)
				(type default)
			)
			(layer "F.Fab")
		)
		(fp_line
			(start -0.12065 0.3048)
			(end -0.67945 0.3048)
			(stroke
				(width 0.1)
				(type default)
			)
			(layer "F.Fab")
		)
		(fp_line
			(start -0.12065 0.2794)
			(end -0.12065 0.3048)
			(stroke
				(width 0.1)
				(type default)
			)
			(layer "F.Fab")
		)
		(fp_line
			(start -0.12065 -0.2794)
			(end 0.12065 -0.2794)
			(stroke
				(width 0.1)
				(type default)
			)
			(layer "F.Fab")
		)
		(fp_line
			(start -0.12065 -0.305054)
			(end -0.12065 -0.2794)
			(stroke
				(width 0.1)
				(type default)
			)
			(layer "F.Fab")
		)
		(fp_line
			(start -0.67945 0.3048)
			(end -0.67945 -0.305054)
			(stroke
				(width 0.1)
				(type default)
			)
			(layer "F.Fab")
		)
		(fp_line
			(start -0.67945 -0.305054)
			(end -0.12065 -0.305054)
			(stroke
				(width 0.1)
				(type default)
			)
			(layer "F.Fab")
		)
		(pad "1" smd circle
			(at -0.40005 0 180)
			(size 0 0)
			(layers "F.Cu" "F.Mask" "F.Paste")
			(net "GPU_3V3IO_RSVD3_FFU")
		)
		(pad "2" smd circle
			(at 0.40005 0 180)
			(size 0 0)
			(layers "F.Cu" "F.Mask" "F.Paste")
			(net "GPU_3V3IO_RSVD3_FFU_ISO")
		)
	)
)
